(kicad_pcb
	(version 20260206)
	(generator "pcbnew")
	(generator_version "10.0")
	(general
		(thickness 1.6)
		(legacy_teardrops no)
	)
	(paper "A4")
	(title_block
		(title "12092022_DA0F0TMDCD0_F0T_Management_Board_D_brd_V3_OCP.brd")
		(comment 1 "Grand Teton / footprints 992-997 of 1440")
	)
	(layers
		(0 "F.Cu" signal "TOP")
		(4 "In1.Cu" signal "GND")
		(6 "In2.Cu" signal "IN1")
		(8 "In3.Cu" signal "GND1")
		(10 "In4.Cu" signal "IN2")
		(12 "In5.Cu" signal "VCC")
		(14 "In6.Cu" signal "VCC1")
		(16 "In7.Cu" signal "IN3")
		(18 "In8.Cu" signal "GND2")
		(20 "In9.Cu" signal "IN4")
		(22 "In10.Cu" signal "GND3")
		(2 "B.Cu" signal "BOTTOM")
		(9 "F.Adhes" user "F.Adhesive")
		(11 "B.Adhes" user "B.Adhesive")
		(13 "F.Paste" user "Package Geometry/Pastemask Top")
		(15 "B.Paste" user "Package Geometry/Pastemask Bottom")
		(5 "F.SilkS" user "Ref Des/Silkscreen Top")
		(7 "B.SilkS" user "Ref Des/Silkscreen Bottom")
		(1 "F.Mask" user "Board Geometry/Soldermask Top")
		(3 "B.Mask" user "Board Geometry/Soldermask Bottom")
		(17 "Dwgs.User" user "User.Drawings")
		(19 "Cmts.User" user "User.Comments")
		(21 "Eco1.User" user "User.Eco1")
		(23 "Eco2.User" user "User.Eco2")
		(25 "Edge.Cuts" user "Board Geometry/Outline")
		(27 "Margin" user)
		(31 "F.CrtYd" user "Package Geometry/Place Bound Top")
		(29 "B.CrtYd" user "Package Geometry/Place Bound Bottom")
		(35 "F.Fab" user "Ref Des/Assembly Top")
		(33 "B.Fab" user "Ref Des/Assembly Bottom")
	)
	(footprint ""
		(layer "B.Cu")
		(at 47.850044 -74.954384)
		(property "Reference" "R775"
			(at 0 0 0)
			(layer "B.SilkS")
			(hide yes)
			(effects
				(font
					(size 1.27 1.27)
				)
				(justify mirror)
			)
		)
		(property "Value" ""
			(at 0 0 0)
			(layer "B.Fab")
			(effects
				(font
					(size 1.27 1.27)
				)
				(justify mirror)
			)
		)
		(duplicate_pad_numbers_are_jumpers no)
		(fp_line
			(start -0.7874 -0.4064)
			(end -0.7874 0.4064)
			(stroke
				(width 0.1524)
				(type default)
			)
			(layer "B.SilkS")
		)
		(fp_line
			(start -0.7874 0.4064)
			(end 0.7874 0.4064)
			(stroke
				(width 0.1524)
				(type default)
			)
			(layer "B.SilkS")
		)
		(fp_line
			(start 0.7874 -0.4064)
			(end -0.7874 -0.4064)
			(stroke
				(width 0.1524)
				(type default)
			)
			(layer "B.SilkS")
		)
		(fp_line
			(start 0.7874 0.4064)
			(end 0.7874 -0.4064)
			(stroke
				(width 0.1524)
				(type default)
			)
			(layer "B.SilkS")
		)
		(fp_line
			(start -0.67945 -0.3048)
			(end -0.67945 0.3048)
			(stroke
				(width 0.1)
				(type default)
			)
			(layer "B.Fab")
		)
		(fp_line
			(start -0.67945 0.3048)
			(end -0.120396 0.3048)
			(stroke
				(width 0.1)
				(type default)
			)
			(layer "B.Fab")
		)
		(fp_line
			(start -0.12065 -0.3048)
			(end -0.67945 -0.3048)
			(stroke
				(width 0.1)
				(type default)
			)
			(layer "B.Fab")
		)
		(fp_line
			(start -0.12065 -0.2794)
			(end -0.12065 -0.3048)
			(stroke
				(width 0.1)
				(type default)
			)
			(layer "B.Fab")
		)
		(fp_line
			(start -0.120396 0.2794)
			(end 0.12065 0.2794)
			(stroke
				(width 0.1)
				(type default)
			)
			(layer "B.Fab")
		)
		(fp_line
			(start -0.120396 0.3048)
			(end -0.120396 0.2794)
			(stroke
				(width 0.1)
				(type default)
			)
			(layer "B.Fab")
		)
		(fp_line
			(start 0.12065 -0.305054)
			(end 0.12065 -0.2794)
			(stroke
				(width 0.1)
				(type default)
			)
			(layer "B.Fab")
		)
		(fp_line
			(start 0.12065 -0.2794)
			(end -0.12065 -0.2794)
			(stroke
				(width 0.1)
				(type default)
			)
			(layer "B.Fab")
		)
		(fp_line
			(start 0.12065 0.2794)
			(end 0.12065 0.3048)
			(stroke
				(width 0.1)
				(type default)
			)
			(layer "B.Fab")
		)
		(fp_line
			(start 0.12065 0.3048)
			(end 0.67945 0.3048)
			(stroke
				(width 0.1)
				(type default)
			)
			(layer "B.Fab")
		)
		(fp_line
			(start 0.67945 -0.305054)
			(end 0.12065 -0.305054)
			(stroke
				(width 0.1)
				(type default)
			)
			(layer "B.Fab")
		)
		(fp_line
			(start 0.67945 0.3048)
			(end 0.67945 -0.305054)
			(stroke
				(width 0.1)
				(type default)
			)
			(layer "B.Fab")
		)
		(pad "1" smd circle
			(at 0.40005 0 180)
			(size 0 0)
			(layers "B.Cu" "B.Mask" "B.Paste")
			(net "BATTERY_DETECT")
		)
		(pad "2" smd circle
			(at -0.40005 0 180)
			(size 0 0)
			(layers "B.Cu" "B.Mask" "B.Paste")
			(net "BATTERY_DETECT_R")
		)
	)
	(footprint ""
		(layer "B.Cu")
		(at 41.9989 -40.9321)
		(property "Reference" "R172"
			(at 0 0 0)
			(layer "B.SilkS")
			(hide yes)
			(effects
				(font
					(size 1.27 1.27)
				)
				(justify mirror)
			)
		)
		(property "Value" ""
			(at 0 0 0)
			(layer "B.Fab")
			(effects
				(font
					(size 1.27 1.27)
				)
				(justify mirror)
			)
		)
		(duplicate_pad_numbers_are_jumpers no)
		(fp_line
			(start -0.7874 -0.4064)
			(end -0.7874 0.4064)
			(stroke
				(width 0.1524)
				(type default)
			)
			(layer "B.SilkS")
		)
		(fp_line
			(start -0.7874 0.4064)
			(end 0.7874 0.4064)
			(stroke
				(width 0.1524)
				(type default)
			)
			(layer "B.SilkS")
		)
		(fp_line
			(start 0.7874 -0.4064)
			(end -0.7874 -0.4064)
			(stroke
				(width 0.1524)
				(type default)
			)
			(layer "B.SilkS")
		)
		(fp_line
			(start 0.7874 0.4064)
			(end 0.7874 -0.4064)
			(stroke
				(width 0.1524)
				(type default)
			)
			(layer "B.SilkS")
		)
		(fp_line
			(start -0.67945 -0.3048)
			(end -0.67945 0.3048)
			(stroke
				(width 0.1)
				(type default)
			)
			(layer "B.Fab")
		)
		(fp_line
			(start -0.67945 0.3048)
			(end -0.120396 0.3048)
			(stroke
				(width 0.1)
				(type default)
			)
			(layer "B.Fab")
		)
		(fp_line
			(start -0.12065 -0.3048)
			(end -0.67945 -0.3048)
			(stroke
				(width 0.1)
				(type default)
			)
			(layer "B.Fab")
		)
		(fp_line
			(start -0.12065 -0.2794)
			(end -0.12065 -0.3048)
			(stroke
				(width 0.1)
				(type default)
			)
			(layer "B.Fab")
		)
		(fp_line
			(start -0.120396 0.2794)
			(end 0.12065 0.2794)
			(stroke
				(width 0.1)
				(type default)
			)
			(layer "B.Fab")
		)
		(fp_line
			(start -0.120396 0.3048)
			(end -0.120396 0.2794)
			(stroke
				(width 0.1)
				(type default)
			)
			(layer "B.Fab")
		)
		(fp_line
			(start 0.12065 -0.305054)
			(end 0.12065 -0.2794)
			(stroke
				(width 0.1)
				(type default)
			)
			(layer "B.Fab")
		)
		(fp_line
			(start 0.12065 -0.2794)
			(end -0.12065 -0.2794)
			(stroke
				(width 0.1)
				(type default)
			)
			(layer "B.Fab")
		)
		(fp_line
			(start 0.12065 0.2794)
			(end 0.12065 0.3048)
			(stroke
				(width 0.1)
				(type default)
			)
			(layer "B.Fab")
		)
		(fp_line
			(start 0.12065 0.3048)
			(end 0.67945 0.3048)
			(stroke
				(width 0.1)
				(type default)
			)
			(layer "B.Fab")
		)
		(fp_line
			(start 0.67945 -0.305054)
			(end 0.12065 -0.305054)
			(stroke
				(width 0.1)
				(type default)
			)
			(layer "B.Fab")
		)
		(fp_line
			(start 0.67945 0.3048)
			(end 0.67945 -0.305054)
			(stroke
				(width 0.1)
				(type default)
			)
			(layer "B.Fab")
		)
		(pad "1" smd circle
			(at 0.40005 0 180)
			(size 0 0)
			(layers "B.Cu" "B.Mask" "B.Paste")
			(net "RMII_TXD0_R")
		)
		(pad "2" smd circle
			(at -0.40005 0 180)
			(size 0 0)
			(layers "B.Cu" "B.Mask" "B.Paste")
			(net "RMII_TXD0")
		)
	)
	(footprint ""
		(layer "B.Cu")
		(at 56.515 -34.671 90)
		(property "Reference" "R146"
			(at 0 0 90)
			(layer "B.SilkS")
			(hide yes)
			(effects
				(font
					(size 1.27 1.27)
				)
				(justify mirror)
			)
		)
		(property "Value" ""
			(at 0 0 90)
			(layer "B.Fab")
			(effects
				(font
					(size 1.27 1.27)
				)
				(justify mirror)
			)
		)
		(duplicate_pad_numbers_are_jumpers no)
		(fp_line
			(start 0.7874 -0.4064)
			(end -0.7874 -0.4064)
			(stroke
				(width 0.1524)
				(type default)
			)
			(layer "B.SilkS")
		)
		(fp_line
			(start -0.7874 -0.4064)
			(end -0.7874 0.4064)
			(stroke
				(width 0.1524)
				(type default)
			)
			(layer "B.SilkS")
		)
		(fp_line
			(start 0.7874 0.4064)
			(end 0.7874 -0.4064)
			(stroke
				(width 0.1524)
				(type default)
			)
			(layer "B.SilkS")
		)
		(fp_line
			(start -0.7874 0.4064)
			(end 0.7874 0.4064)
			(stroke
				(width 0.1524)
				(type default)
			)
			(layer "B.SilkS")
		)
		(fp_line
			(start 0.67945 -0.305054)
			(end 0.12065 -0.305054)
			(stroke
				(width 0.1)
				(type default)
			)
			(layer "B.Fab")
		)
		(fp_line
			(start 0.12065 -0.305054)
			(end 0.12065 -0.2794)
			(stroke
				(width 0.1)
				(type default)
			)
			(layer "B.Fab")
		)
		(fp_line
			(start -0.12065 -0.3048)
			(end -0.67945 -0.3048)
			(stroke
				(width 0.1)
				(type default)
			)
			(layer "B.Fab")
		)
		(fp_line
			(start -0.67945 -0.3048)
			(end -0.67945 0.3048)
			(stroke
				(width 0.1)
				(type default)
			)
			(layer "B.Fab")
		)
		(fp_line
			(start 0.12065 -0.2794)
			(end -0.12065 -0.2794)
			(stroke
				(width 0.1)
				(type default)
			)
			(layer "B.Fab")
		)
		(fp_line
			(start -0.12065 -0.2794)
			(end -0.12065 -0.3048)
			(stroke
				(width 0.1)
				(type default)
			)
			(layer "B.Fab")
		)
		(fp_line
			(start 0.12065 0.2794)
			(end 0.12065 0.3048)
			(stroke
				(width 0.1)
				(type default)
			)
			(layer "B.Fab")
		)
		(fp_line
			(start -0.120396 0.2794)
			(end 0.12065 0.2794)
			(stroke
				(width 0.1)
				(type default)
			)
			(layer "B.Fab")
		)
		(fp_line
			(start 0.67945 0.3048)
			(end 0.67945 -0.305054)
			(stroke
				(width 0.1)
				(type default)
			)
			(layer "B.Fab")
		)
		(fp_line
			(start 0.12065 0.3048)
			(end 0.67945 0.3048)
			(stroke
				(width 0.1)
				(type default)
			)
			(layer "B.Fab")
		)
		(fp_line
			(start -0.120396 0.3048)
			(end -0.120396 0.2794)
			(stroke
				(width 0.1)
				(type default)
			)
			(layer "B.Fab")
		)
		(fp_line
			(start -0.67945 0.3048)
			(end -0.120396 0.3048)
			(stroke
				(width 0.1)
				(type default)
			)
			(layer "B.Fab")
		)
		(pad "1" smd circle
			(at 0.40005 0 270)
			(size 0 0)
			(layers "B.Cu" "B.Mask" "B.Paste")
			(net "SMB_BMC_MM8_R_SCL")
		)
		(pad "2" smd circle
			(at -0.40005 0 270)
			(size 0 0)
			(layers "B.Cu" "B.Mask" "B.Paste")
			(net "SMB_BMC_MM8_SCL")
		)
	)
	(footprint ""
		(layer "B.Cu")
		(at 51.2445 -91.3765 180)
		(property "Reference" "R735"
			(at 0 0 0)
			(layer "B.SilkS")
			(hide yes)
			(effects
				(font
					(size 1.27 1.27)
				)
				(justify mirror)
			)
		)
		(property "Value" ""
			(at 0 0 0)
			(layer "B.Fab")
			(effects
				(font
					(size 1.27 1.27)
				)
				(justify mirror)
			)
		)
		(duplicate_pad_numbers_are_jumpers no)
		(fp_line
			(start 0.7874 0.4064)
			(end 0.7874 -0.4064)
			(stroke
				(width 0.1524)
				(type default)
			)
			(layer "B.SilkS")
		)
		(fp_line
			(start 0.7874 -0.4064)
			(end -0.7874 -0.4064)
			(stroke
				(width 0.1524)
				(type default)
			)
			(layer "B.SilkS")
		)
		(fp_line
			(start -0.7874 0.4064)
			(end 0.7874 0.4064)
			(stroke
				(width 0.1524)
				(type default)
			)
			(layer "B.SilkS")
		)
		(fp_line
			(start -0.7874 -0.4064)
			(end -0.7874 0.4064)
			(stroke
				(width 0.1524)
				(type default)
			)
			(layer "B.SilkS")
		)
		(fp_line
			(start 0.67945 0.3048)
			(end 0.67945 -0.305054)
			(stroke
				(width 0.1)
				(type default)
			)
			(layer "B.Fab")
		)
		(fp_line
			(start 0.67945 -0.305054)
			(end 0.12065 -0.305054)
			(stroke
				(width 0.1)
				(type default)
			)
			(layer "B.Fab")
		)
		(fp_line
			(start 0.12065 0.3048)
			(end 0.67945 0.3048)
			(stroke
				(width 0.1)
				(type default)
			)
			(layer "B.Fab")
		)
		(fp_line
			(start 0.12065 0.2794)
			(end 0.12065 0.3048)
			(stroke
				(width 0.1)
				(type default)
			)
			(layer "B.Fab")
		)
		(fp_line
			(start 0.12065 -0.2794)
			(end -0.12065 -0.2794)
			(stroke
				(width 0.1)
				(type default)
			)
			(layer "B.Fab")
		)
		(fp_line
			(start 0.12065 -0.305054)
			(end 0.12065 -0.2794)
			(stroke
				(width 0.1)
				(type default)
			)
			(layer "B.Fab")
		)
		(fp_line
			(start -0.120396 0.3048)
			(end -0.120396 0.2794)
			(stroke
				(width 0.1)
				(type default)
			)
			(layer "B.Fab")
		)
		(fp_line
			(start -0.120396 0.2794)
			(end 0.12065 0.2794)
			(stroke
				(width 0.1)
				(type default)
			)
			(layer "B.Fab")
		)
		(fp_line
			(start -0.12065 -0.2794)
			(end -0.12065 -0.3048)
			(stroke
				(width 0.1)
				(type default)
			)
			(layer "B.Fab")
		)
		(fp_line
			(start -0.12065 -0.3048)
			(end -0.67945 -0.3048)
			(stroke
				(width 0.1)
				(type default)
			)
			(layer "B.Fab")
		)
		(fp_line
			(start -0.67945 0.3048)
			(end -0.120396 0.3048)
			(stroke
				(width 0.1)
				(type default)
			)
			(layer "B.Fab")
		)
		(fp_line
			(start -0.67945 -0.3048)
			(end -0.67945 0.3048)
			(stroke
				(width 0.1)
				(type default)
			)
			(layer "B.Fab")
		)
		(pad "1" smd circle
			(at 0.40005 0)
			(size 0 0)
			(layers "B.Cu" "B.Mask" "B.Paste")
			(net "P3V3_AUX")
		)
		(pad "2" smd circle
			(at -0.40005 0)
			(size 0 0)
			(layers "B.Cu" "B.Mask" "B.Paste")
			(net "FM_UART_SWITCH_N")
		)
	)
	(footprint ""
		(layer "B.Cu")
		(at 53.5432 -34.637726 90)
		(property "Reference" "R826"
			(at 0 0 90)
			(layer "B.SilkS")
			(hide yes)
			(effects
				(font
					(size 1.27 1.27)
				)
				(justify mirror)
			)
		)
		(property "Value" ""
			(at 0 0 90)
			(layer "B.Fab")
			(effects
				(font
					(size 1.27 1.27)
				)
				(justify mirror)
			)
		)
		(duplicate_pad_numbers_are_jumpers no)
		(fp_line
			(start 0.7874 -0.4064)
			(end -0.7874 -0.4064)
			(stroke
				(width 0.1524)
				(type default)
			)
			(layer "B.SilkS")
		)
		(fp_line
			(start -0.7874 -0.4064)
			(end -0.7874 0.4064)
			(stroke
				(width 0.1524)
				(type default)
			)
			(layer "B.SilkS")
		)
		(fp_line
			(start 0.7874 0.4064)
			(end 0.7874 -0.4064)
			(stroke
				(width 0.1524)
				(type default)
			)
			(layer "B.SilkS")
		)
		(fp_line
			(start -0.7874 0.4064)
			(end 0.7874 0.4064)
			(stroke
				(width 0.1524)
				(type default)
			)
			(layer "B.SilkS")
		)
		(fp_line
			(start 0.67945 -0.305054)
			(end 0.12065 -0.305054)
			(stroke
				(width 0.1)
				(type default)
			)
			(layer "B.Fab")
		)
		(fp_line
			(start 0.12065 -0.305054)
			(end 0.12065 -0.2794)
			(stroke
				(width 0.1)
				(type default)
			)
			(layer "B.Fab")
		)
		(fp_line
			(start -0.12065 -0.3048)
			(end -0.67945 -0.3048)
			(stroke
				(width 0.1)
				(type default)
			)
			(layer "B.Fab")
		)
		(fp_line
			(start -0.67945 -0.3048)
			(end -0.67945 0.3048)
			(stroke
				(width 0.1)
				(type default)
			)
			(layer "B.Fab")
		)
		(fp_line
			(start 0.12065 -0.2794)
			(end -0.12065 -0.2794)
			(stroke
				(width 0.1)
				(type default)
			)
			(layer "B.Fab")
		)
		(fp_line
			(start -0.12065 -0.2794)
			(end -0.12065 -0.3048)
			(stroke
				(width 0.1)
				(type default)
			)
			(layer "B.Fab")
		)
		(fp_line
			(start 0.12065 0.2794)
			(end 0.12065 0.3048)
			(stroke
				(width 0.1)
				(type default)
			)
			(layer "B.Fab")
		)
		(fp_line
			(start -0.120396 0.2794)
			(end 0.12065 0.2794)
			(stroke
				(width 0.1)
				(type default)
			)
			(layer "B.Fab")
		)
		(fp_line
			(start 0.67945 0.3048)
			(end 0.67945 -0.305054)
			(stroke
				(width 0.1)
				(type default)
			)
			(layer "B.Fab")
		)
		(fp_line
			(start 0.12065 0.3048)
			(end 0.67945 0.3048)
			(stroke
				(width 0.1)
				(type default)
			)
			(layer "B.Fab")
		)
		(fp_line
			(start -0.120396 0.3048)
			(end -0.120396 0.2794)
			(stroke
				(width 0.1)
				(type default)
			)
			(layer "B.Fab")
		)
		(fp_line
			(start -0.67945 0.3048)
			(end -0.120396 0.3048)
			(stroke
				(width 0.1)
				(type default)
			)
			(layer "B.Fab")
		)
		(pad "1" smd circle
			(at 0.40005 0 270)
			(size 0 0)
			(layers "B.Cu" "B.Mask" "B.Paste")
			(net "IRQ_PCH_SCI_WHEA_R_N")
		)
		(pad "2" smd circle
			(at -0.40005 0 270)
			(size 0 0)
			(layers "B.Cu" "B.Mask" "B.Paste")
			(net "IRQ_PCH_SCI_WHEA_N")
		)
	)
	(footprint ""
		(layer "B.Cu")
		(at 45.0342 -55.4482 90)
		(property "Reference" "R489"
			(at 0 0 90)
			(layer "B.SilkS")
			(hide yes)
			(effects
				(font
					(size 1.27 1.27)
				)
				(justify mirror)
			)
		)
		(property "Value" ""
			(at 0 0 90)
			(layer "B.Fab")
			(effects
				(font
					(size 1.27 1.27)
				)
				(justify mirror)
			)
		)
		(duplicate_pad_numbers_are_jumpers no)
		(fp_line
			(start 0.7874 -0.4064)
			(end -0.7874 -0.4064)
			(stroke
				(width 0.1524)
				(type default)
			)
			(layer "B.SilkS")
		)
		(fp_line
			(start -0.7874 -0.4064)
			(end -0.7874 0.4064)
			(stroke
				(width 0.1524)
				(type default)
			)
			(layer "B.SilkS")
		)
		(fp_line
			(start 0.7874 0.4064)
			(end 0.7874 -0.4064)
			(stroke
				(width 0.1524)
				(type default)
			)
			(layer "B.SilkS")
		)
		(fp_line
			(start -0.7874 0.4064)
			(end 0.7874 0.4064)
			(stroke
				(width 0.1524)
				(type default)
			)
			(layer "B.SilkS")
		)
		(fp_line
			(start 0.67945 -0.305054)
			(end 0.12065 -0.305054)
			(stroke
				(width 0.1)
				(type default)
			)
			(layer "B.Fab")
		)
		(fp_line
			(start 0.12065 -0.305054)
			(end 0.12065 -0.2794)
			(stroke
				(width 0.1)
				(type default)
			)
			(layer "B.Fab")
		)
		(fp_line
			(start -0.12065 -0.3048)
			(end -0.67945 -0.3048)
			(stroke
				(width 0.1)
				(type default)
			)
			(layer "B.Fab")
		)
		(fp_line
			(start -0.67945 -0.3048)
			(end -0.67945 0.3048)
			(stroke
				(width 0.1)
				(type default)
			)
			(layer "B.Fab")
		)
		(fp_line
			(start 0.12065 -0.2794)
			(end -0.12065 -0.2794)
			(stroke
				(width 0.1)
				(type default)
			)
			(layer "B.Fab")
		)
		(fp_line
			(start -0.12065 -0.2794)
			(end -0.12065 -0.3048)
			(stroke
				(width 0.1)
				(type default)
			)
			(layer "B.Fab")
		)
		(fp_line
			(start 0.12065 0.2794)
			(end 0.12065 0.3048)
			(stroke
				(width 0.1)
				(type default)
			)
			(layer "B.Fab")
		)
		(fp_line
			(start -0.120396 0.2794)
			(end 0.12065 0.2794)
			(stroke
				(width 0.1)
				(type default)
			)
			(layer "B.Fab")
		)
		(fp_line
			(start 0.67945 0.3048)
			(end 0.67945 -0.305054)
			(stroke
				(width 0.1)
				(type default)
			)
			(layer "B.Fab")
		)
		(fp_line
			(start 0.12065 0.3048)
			(end 0.67945 0.3048)
			(stroke
				(width 0.1)
				(type default)
			)
			(layer "B.Fab")
		)
		(fp_line
			(start -0.120396 0.3048)
			(end -0.120396 0.2794)
			(stroke
				(width 0.1)
				(type default)
			)
			(layer "B.Fab")
		)
		(fp_line
			(start -0.67945 0.3048)
			(end -0.120396 0.3048)
			(stroke
				(width 0.1)
				(type default)
			)
			(layer "B.Fab")
		)
		(pad "1" smd circle
			(at 0.40005 0 270)
			(size 0 0)
			(layers "B.Cu" "B.Mask" "B.Paste")
			(net "FM_SOL_UART_CH_SEL")
		)
		(pad "2" smd circle
			(at -0.40005 0 270)
			(size 0 0)
			(layers "B.Cu" "B.Mask" "B.Paste")
			(net "FM_SOL_UART_CH_SEL_R1")
		)
	)
)
